# BASEBOARD_FAB2 (Tioga Pass) — schematic netlist excerpt (pin names and nets, part order shuffled) for the footprints in the layout excerpt that follows; sources: Cadence DE-HDL packaged netlist, KiCad conversion of Wiwynn_Tioga_Pass_MB.brd

J1G1  SCONN288_H44441004  SCONN  pkg PIP  page 77
  \12v\(1)  = P12V_NVDIMM_GHJ
  VSS(93)  = GND
  DQ(4)  = M_G_DQ<5>
  VSS(92)  = GND
  DQ(0)  = M_G_DQ<1>
  VSS(91)  = GND
  DQS9P  = M_G_DQS_DP<9>
  DQS9N  = M_G_DQS_DN<9>
  VSS(90)  = GND
  DQ(6)  = M_G_DQ<7>
  VSS(89)  = GND
  DQ(2)  = M_G_DQ<3>
  VSS(88)  = GND
  DQ(12)  = M_G_DQ<13>
  VSS(87)  = GND
  DQ(8)  = M_G_DQ<9>
  VSS(86)  = GND
  DQS10P  = M_G_DQS_DP<10>
  DQS10N  = M_G_DQS_DN<10>
  VSS(85)  = GND
  DQ(14)  = M_G_DQ<15>
  VSS(84)  = GND
  DQ(10)  = M_G_DQ<11>
  VSS(83)  = GND
  DQ(20)  = M_G_DQ<21>
  VSS(82)  = GND
  DQ(16)  = M_G_DQ<17>
  VSS(81)  = GND
  DQS11P  = M_G_DQS_DP<11>
  DQS11N  = M_G_DQS_DN<11>
  VSS(80)  = GND
  DQ(22)  = M_G_DQ<23>
  VSS(79)  = GND
  DQ(18)  = M_G_DQ<19>
  VSS(78)  = GND
  DQ(28)  = M_G_DQ<29>
  VSS(77)  = GND
  DQ(24)  = M_G_DQ<25>
  VSS(76)  = GND
  DQS12P  = M_G_DQS_DP<12>
  DQS12N  = M_G_DQS_DN<12>
  VSS(75)  = GND
  DQ(30)  = M_G_DQ<31>
  VSS(74)  = GND
  DQ(26)  = M_G_DQ<27>
  VSS(73)  = GND
  CB(4)  = M_G_ECC<5>
  VSS(72)  = GND
  CB(0)  = M_G_ECC<1>
  VSS(71)  = GND
  DQS17P  = M_G_DQS_DP<17>
  DQS17N  = M_G_DQS_DN<17>
  VSS(70)  = GND
  CB(6)  = M_G_ECC<7>
  VSS(69)  = GND
  CB(2)  = M_G_ECC<3>
  VSS(68)  = GND
  RESET_N  = M_GHJ_RST_N
  VDD(25)  = PVDDQ_GHJ
  CKE(0)  = M_G_CKE<0>
  VDD(24)  = PVDDQ_GHJ
  ACT_N  = M_G_ACT_N
  BG(0)  = M_G_BG<0>
  VDD(23)  = PVDDQ_GHJ
  A12  = M_G_MA<12>
  A9  = M_G_MA<9>
  VDD(22)  = PVDDQ_GHJ
  A8  = M_G_MA<8>
  A6  = M_G_MA<6>
  VDD(21)  = PVDDQ_GHJ
  A3  = M_G_MA<3>
  A1  = M_G_MA<1>
  VDD(20)  = PVDDQ_GHJ
  CK0P  = M_G_CLK_DP<0>
  CK0N  = M_G_CLK_DN<0>
  VDD(19)  = PVDDQ_GHJ
  VTT(1)  = PVTT_GHJ
  EVENT_N  = FM_DIMM_EVENT_COD_N
  A0  = M_G_MA<0>
  VDD(18)  = PVDDQ_GHJ
  BA(0)  = M_G_BA<0>
  A16_RAS_N  = M_G_MA<16>
  VDD(17)  = PVDDQ_GHJ
  S0_N  = M_G_CS_N<0>
  VDD(16)  = PVDDQ_GHJ
  A15_CAS_N  = M_G_MA<15>
  ODT(0)  = M_G_ODT<0>
  VDD(15)  = PVDDQ_GHJ
  S1_N  = M_G_CS_N<1>
  VDD(14)  = PVDDQ_GHJ
  ODT(1)  = M_G_ODT<1>
  VDD(13)  = PVDDQ_GHJ
  S2_N_C(0)  = M_G_CS_N<2>
  VSS(67)  = GND
  DQ(36)  = M_G_DQ<37>
  VSS(66)  = GND
  DQ(32)  = M_G_DQ<33>
  VSS(65)  = GND
  DQS13P  = M_G_DQS_DP<13>
  DQS13N  = M_G_DQS_DN<13>
  VSS(64)  = GND
  DQ(38)  = M_G_DQ<39>
  VSS(63)  = GND
  DQ(34)  = M_G_DQ<35>
  VSS(62)  = GND
  DQ(44)  = M_G_DQ<45>
  VSS(61)  = GND
  DQ(40)  = M_G_DQ<41>
  VSS(60)  = GND
  DQS14P  = M_G_DQS_DP<14>
  DQS14N  = M_G_DQS_DN<14>
  VSS(59)  = GND
  DQ(46)  = M_G_DQ<47>
  VSS(58)  = GND
  DQ(42)  = M_G_DQ<43>
  VSS(57)  = GND
  DQ(52)  = M_G_DQ<53>
  VSS(56)  = GND
  DQ(48)  = M_G_DQ<49>
  VSS(55)  = GND
  DQS15P  = M_G_DQS_DP<15>
  DQS15N  = M_G_DQS_DN<15>
  VSS(54)  = GND
  DQ(54)  = M_G_DQ<55>
  VSS(53)  = GND
  DQ(50)  = M_G_DQ<51>
  VSS(52)  = GND
  DQ(60)  = M_G_DQ<61>
  VSS(51)  = GND
  DQ(56)  = M_G_DQ<57>
  VSS(50)  = GND
  DQS16P  = M_G_DQS_DP<16>
  DQS16N  = M_G_DQS_DN<16>
  VSS(49)  = GND
  DQ(62)  = M_G_DQ<63>
  VSS(48)  = GND
  DQ(58)  = M_G_DQ<59>
  VSS(47)  = GND
  SA(0)  = GND
  SA(1)  = GND
  SCL  = SMB_DDR_GHJ_VPP_SCL
  VPP(4)  = PVPP_GHJ
  VPP(3)  = PVPP_GHJ
  RFU(2)  = TP_CH_G_DIMM_G0_RFU_2
  \12v\(0)  = P12V_NVDIMM_GHJ
  VREFCA  = M_G_VREF
  VSS(46)  = GND
  DQ(5)  = M_G_DQ<4>
  VSS(45)  = GND
  DQ(1)  = M_G_DQ<0>
  VSS(44)  = GND
  DQS0N  = M_G_DQS_DN<0>
  DQS0P  = M_G_DQS_DP<0>
  VSS(43)  = GND
  DQ(7)  = M_G_DQ<6>
  VSS(42)  = GND
  DQ(3)  = M_G_DQ<2>
  VSS(41)  = GND
  DQ(13)  = M_G_DQ<12>
  VSS(40)  = GND
  DQ(9)  = M_G_DQ<8>
  VSS(39)  = GND
  DQS1N  = M_G_DQS_DN<1>
  DQS1P  = M_G_DQS_DP<1>
  VSS(38)  = GND
  DQ(15)  = M_G_DQ<14>
  VSS(37)  = GND
  DQ(11)  = M_G_DQ<10>
  VSS(36)  = GND
  DQ(21)  = M_G_DQ<20>
  VSS(35)  = GND
  DQ(17)  = M_G_DQ<16>
  VSS(34)  = GND
  DQS2N  = M_G_DQS_DN<2>
  DQS2P  = M_G_DQS_DP<2>
  VSS(33)  = GND
  DQ(23)  = M_G_DQ<22>
  VSS(32)  = GND
  DQ(19)  = M_G_DQ<18>
  VSS(31)  = GND
  DQ(29)  = M_G_DQ<28>
  VSS(30)  = GND
  DQ(25)  = M_G_DQ<24>
  VSS(29)  = GND
  DQS3N  = M_G_DQS_DN<3>
  DQS3P  = M_G_DQS_DP<3>
  VSS(28)  = GND
  DQ(31)  = M_G_DQ<30>
  VSS(27)  = GND
  DQ(27)  = M_G_DQ<26>
  VSS(26)  = GND
  CB(5)  = M_G_ECC<4>
  VSS(25)  = GND
  CB(1)  = M_G_ECC<0>
  VSS(24)  = GND
  DQS8N  = M_G_DQS_DN<8>
  DQS8P  = M_G_DQS_DP<8>
  VSS(23)  = GND
  CB(7)  = M_G_ECC<6>
  VSS(22)  = GND
  CB(3)  = M_G_ECC<2>
  VSS(21)  = GND
  CKE(1)  = M_G_CKE<1>
  VDD(12)  = PVDDQ_GHJ
  RFU(0)  = TP_CH_G_DIMM_G0_RFU_0
  VDD(11)  = PVDDQ_GHJ
  BG(1)  = M_G_BG<1>
  ALERT_N  = M_G_ALERT_N
  VDD(10)  = PVDDQ_GHJ
  A11  = M_G_MA<11>
  A7  = M_G_MA<7>
  VDD(9)  = PVDDQ_GHJ
  A5  = M_G_MA<5>
  A4  = M_G_MA<4>
  VDD(8)  = PVDDQ_GHJ
  A2  = M_G_MA<2>
  VDD(7)  = PVDDQ_GHJ
  CK1P  = M_G_CLK_DP<1>
  CK1N  = M_G_CLK_DN<1>
  VDD(6)  = PVDDQ_GHJ
  VTT(0)  = PVTT_GHJ
  PAR  = M_G_PAR
  VDD(5)  = PVDDQ_GHJ
  BA(1)  = M_G_BA<1>
  A10  = M_G_MA<10>
  VDD(4)  = PVDDQ_GHJ
  RFU(1)  = TP_CH_G_DIMM_G0_RFU_1
  A14_WE_N  = M_G_MA<14>
  VDD(3)  = PVDDQ_GHJ
  SAVE_N_NC  = FM_ADR_COMPLETE_GHJ_N
  VDD(2)  = PVDDQ_GHJ
  A13  = M_G_MA<13>
  VDD(1)  = PVDDQ_GHJ
  A17  = M_G_MA<17>
  C(2)  = M_G_C<2>
  VDD(0)  = PVDDQ_GHJ
  S3_N_C(1)  = M_G_CS_N<3>
  SA(2)  = GND
  VSS(20)  = GND
  DQ(37)  = M_G_DQ<36>
  VSS(19)  = GND
  DQ(33)  = M_G_DQ<32>
  VSS(18)  = GND
  DQS4N  = M_G_DQS_DN<4>
  DQS4P  = M_G_DQS_DP<4>
  VSS(17)  = GND
  DQ(39)  = M_G_DQ<38>
  VSS(16)  = GND
  DQ(35)  = M_G_DQ<34>
  VSS(15)  = GND
  DQ(45)  = M_G_DQ<44>
  VSS(14)  = GND
  DQ(41)  = M_G_DQ<40>
  VSS(13)  = GND
  DQS5N  = M_G_DQS_DN<5>
  DQS5P  = M_G_DQS_DP<5>
  VSS(12)  = GND
  DQ(47)  = M_G_DQ<46>
  VSS(11)  = GND
  DQ(43)  = M_G_DQ<42>
  VSS(10)  = GND
  DQ(53)  = M_G_DQ<52>
  VSS(9)  = GND
  DQ(49)  = M_G_DQ<48>
  VSS(8)  = GND
  DQS6N  = M_G_DQS_DN<6>
  DQS6P  = M_G_DQS_DP<6>
  VSS(7)  = GND
  DQ(55)  = M_G_DQ<54>
  VSS(6)  = GND
  DQ(51)  = M_G_DQ<50>
  VSS(5)  = GND
  DQ(61)  = M_G_DQ<60>
  VSS(4)  = GND
  DQ(57)  = M_G_DQ<56>
  VSS(3)  = GND
  DQS7N  = M_G_DQS_DN<7>
  DQS7P  = M_G_DQS_DP<7>
  VSS(2)  = GND
  DQ(63)  = M_G_DQ<62>
  VSS(1)  = GND
  DQ(59)  = M_G_DQ<58>
  VSS(0)  = GND
  VDDSPD  = PVPP_GHJ
  SDA  = SMB_DDR_GHJ_VPP_SDA
  VPP(1)  = PVPP_GHJ
  VPP(0)  = PVPP_GHJ
  VPP(2)  = PVPP_GHJ

(kicad_pcb
	(version 20260206)
	(generator "pcbnew")
	(generator_version "10.0")
	(general
		(thickness 1.6)
		(legacy_teardrops no)
	)
	(paper "A4")
	(title_block
		(title "Wiwynn_Tioga_Pass_MB.brd")
		(comment 1 "Tioga Pass / footprint 2018 of 4770 (J1G1), pads 1-50 of 291")
	)
	(layers
		(0 "F.Cu" signal "TOP")
		(4 "In1.Cu" signal "L2GND")
		(6 "In2.Cu" signal "L3")
		(8 "In3.Cu" signal "L4GND")
		(10 "In4.Cu" signal "L5")
		(12 "In5.Cu" signal "L6GND")
		(14 "In6.Cu" signal "L7VCC")
		(16 "In7.Cu" signal "L8VCC")
		(18 "In8.Cu" signal "L9GND")
		(20 "In9.Cu" signal "L10")
		(22 "In10.Cu" signal "L11GND")
		(24 "In11.Cu" signal "L12")
		(26 "In12.Cu" signal "L13GND")
		(2 "B.Cu" signal "BOTTOM")
		(9 "F.Adhes" user "F.Adhesive")
		(11 "B.Adhes" user "B.Adhesive")
		(13 "F.Paste" user "Package Geometry/Pastemask Top")
		(15 "B.Paste" user "Package Geometry/Pastemask Bottom")
		(5 "F.SilkS" user "Ref Des/Silkscreen Top")
		(7 "B.SilkS" user "Ref Des/Silkscreen Bottom")
		(1 "F.Mask" user "Board Geometry/Soldermask Top")
		(3 "B.Mask" user "Board Geometry/Soldermask Bottom")
		(17 "Dwgs.User" user "User.Drawings")
		(19 "Cmts.User" user "User.Comments")
		(21 "Eco1.User" user "User.Eco1")
		(23 "Eco2.User" user "User.Eco2")
		(25 "Edge.Cuts" user "Board Geometry/Outline")
		(27 "Margin" user)
		(31 "F.CrtYd" user "Package Geometry/Place Bound Top")
		(29 "B.CrtYd" user "Package Geometry/Place Bound Bottom")
		(35 "F.Fab" user "Ref Des/Assembly Top")
		(33 "B.Fab" user "Ref Des/Assembly Bottom")
	)
	(footprint ""
		(layer "F.Cu")
		(at 29.699458 -15.423642 90)
		(property "Reference" "J1G1"
			(at 9.314688 35.070542 0)
			(unlocked yes)
			(layer "F.SilkS")
			(effects
				(font
					(size 0.7874 0.5842)
					(thickness 0.1524)
				)
				(justify left)
			)
		)
		(property "Value" ""
			(at 0 0 90)
			(layer "F.Fab")
			(effects
				(font
					(size 1.27 1.27)
				)
			)
		)
		(duplicate_pad_numbers_are_jumpers no)
		(pad "" thru_hole circle
			(at 2.29997 -5.649976 90)
			(size 2.8194 2.8194)
			(drill 2.4384)
			(layers "*.Cu" "*.Mask")
			(remove_unused_layers no)
			(clearance 0.127)
			(thermal_gap 0.127)
		)
		(pad "" thru_hole oval
			(at 2.29997 68.90004 90)
			(size 2.8194 1.5748)
			(drill oval 2.4384 1.1938)
			(layers "*.Cu" "*.Mask")
			(remove_unused_layers no)
			(clearance 0.127)
			(thermal_gap 0.127)
		)
		(pad "" thru_hole circle
			(at 2.29997 132.299964 90)
			(size 2.8194 2.8194)
			(drill 2.4384)
			(layers "*.Cu" "*.Mask")
			(remove_unused_layers no)
			(clearance 0.127)
			(thermal_gap 0.127)
		)
		(pad "1" smd rect
			(at 0 0 90)
			(size 1.8034 0.508)
			(layers "F.Cu" "F.Mask" "F.Paste")
			(net "P12V_NVDIMM_GHJ")
		)
		(pad "2" smd rect
			(at 0 0.849884 90)
			(size 1.8034 0.508)
			(layers "F.Cu" "F.Mask" "F.Paste")
			(net "GND")
		)
		(pad "3" smd rect
			(at 0 1.700022 90)
			(size 1.8034 0.508)
			(layers "F.Cu" "F.Mask" "F.Paste")
			(net "M_G_DQ<5>")
		)
		(pad "4" smd rect
			(at 0 2.549906 90)
			(size 1.8034 0.508)
			(layers "F.Cu" "F.Mask" "F.Paste")
			(net "GND")
		)
		(pad "5" smd rect
			(at 0 3.400044 90)
			(size 1.8034 0.508)
			(layers "F.Cu" "F.Mask" "F.Paste")
			(net "M_G_DQ<1>")
		)
		(pad "6" smd rect
			(at 0 4.249928 90)
			(size 1.8034 0.508)
			(layers "F.Cu" "F.Mask" "F.Paste")
			(net "GND")
		)
		(pad "7" smd rect
			(at 0 5.100066 90)
			(size 1.8034 0.508)
			(layers "F.Cu" "F.Mask" "F.Paste")
			(net "M_G_DQS_DP<9>")
		)
		(pad "8" smd rect
			(at 0 5.94995 90)
			(size 1.8034 0.508)
			(layers "F.Cu" "F.Mask" "F.Paste")
			(net "M_G_DQS_DN<9>")
		)
		(pad "9" smd rect
			(at 0 6.800088 90)
			(size 1.8034 0.508)
			(layers "F.Cu" "F.Mask" "F.Paste")
			(net "GND")
		)
		(pad "10" smd rect
			(at 0 7.649972 90)
			(size 1.8034 0.508)
			(layers "F.Cu" "F.Mask" "F.Paste")
			(net "M_G_DQ<7>")
		)
		(pad "11" smd rect
			(at 0 8.50011 90)
			(size 1.8034 0.508)
			(layers "F.Cu" "F.Mask" "F.Paste")
			(net "GND")
		)
		(pad "12" smd rect
			(at 0 9.349994 90)
			(size 1.8034 0.508)
			(layers "F.Cu" "F.Mask" "F.Paste")
			(net "M_G_DQ<3>")
		)
		(pad "13" smd rect
			(at 0 10.199878 90)
			(size 1.8034 0.508)
			(layers "F.Cu" "F.Mask" "F.Paste")
			(net "GND")
		)
		(pad "14" smd rect
			(at 0 11.050016 90)
			(size 1.8034 0.508)
			(layers "F.Cu" "F.Mask" "F.Paste")
			(net "M_G_DQ<13>")
		)
		(pad "15" smd rect
			(at 0 11.8999 90)
			(size 1.8034 0.508)
			(layers "F.Cu" "F.Mask" "F.Paste")
			(net "GND")
		)
		(pad "16" smd rect
			(at 0 12.750038 90)
			(size 1.8034 0.508)
			(layers "F.Cu" "F.Mask" "F.Paste")
			(net "M_G_DQ<9>")
		)
		(pad "17" smd rect
			(at 0 13.599922 90)
			(size 1.8034 0.508)
			(layers "F.Cu" "F.Mask" "F.Paste")
			(net "GND")
		)
		(pad "18" smd rect
			(at 0 14.45006 90)
			(size 1.8034 0.508)
			(layers "F.Cu" "F.Mask" "F.Paste")
			(net "M_G_DQS_DP<10>")
		)
		(pad "19" smd rect
			(at 0 15.299944 90)
			(size 1.8034 0.508)
			(layers "F.Cu" "F.Mask" "F.Paste")
			(net "M_G_DQS_DN<10>")
		)
		(pad "20" smd rect
			(at 0 16.150082 90)
			(size 1.8034 0.508)
			(layers "F.Cu" "F.Mask" "F.Paste")
			(net "GND")
		)
		(pad "21" smd rect
			(at 0 16.999966 90)
			(size 1.8034 0.508)
			(layers "F.Cu" "F.Mask" "F.Paste")
			(net "M_G_DQ<15>")
		)
		(pad "22" smd rect
			(at 0 17.850104 90)
			(size 1.8034 0.508)
			(layers "F.Cu" "F.Mask" "F.Paste")
			(net "GND")
		)
		(pad "23" smd rect
			(at 0 18.699988 90)
			(size 1.8034 0.508)
			(layers "F.Cu" "F.Mask" "F.Paste")
			(net "M_G_DQ<11>")
		)
		(pad "24" smd rect
			(at 0 19.550126 90)
			(size 1.8034 0.508)
			(layers "F.Cu" "F.Mask" "F.Paste")
			(net "GND")
		)
		(pad "25" smd rect
			(at 0 20.40001 90)
			(size 1.8034 0.508)
			(layers "F.Cu" "F.Mask" "F.Paste")
			(net "M_G_DQ<21>")
		)
		(pad "26" smd rect
			(at 0 21.249894 90)
			(size 1.8034 0.508)
			(layers "F.Cu" "F.Mask" "F.Paste")
			(net "GND")
		)
		(pad "27" smd rect
			(at 0 22.100032 90)
			(size 1.8034 0.508)
			(layers "F.Cu" "F.Mask" "F.Paste")
			(net "M_G_DQ<17>")
		)
		(pad "28" smd rect
			(at 0 22.949916 90)
			(size 1.8034 0.508)
			(layers "F.Cu" "F.Mask" "F.Paste")
			(net "GND")
		)
		(pad "29" smd rect
			(at 0 23.800054 90)
			(size 1.8034 0.508)
			(layers "F.Cu" "F.Mask" "F.Paste")
			(net "M_G_DQS_DP<11>")
		)
		(pad "30" smd rect
			(at 0 24.649938 90)
			(size 1.8034 0.508)
			(layers "F.Cu" "F.Mask" "F.Paste")
			(net "M_G_DQS_DN<11>")
		)
		(pad "31" smd rect
			(at 0 25.500076 90)
			(size 1.8034 0.508)
			(layers "F.Cu" "F.Mask" "F.Paste")
			(net "GND")
		)
		(pad "32" smd rect
			(at 0 26.34996 90)
			(size 1.8034 0.508)
			(layers "F.Cu" "F.Mask" "F.Paste")
			(net "M_G_DQ<23>")
		)
		(pad "33" smd rect
			(at 0 27.200098 90)
			(size 1.8034 0.508)
			(layers "F.Cu" "F.Mask" "F.Paste")
			(net "GND")
		)
		(pad "34" smd rect
			(at 0 28.049982 90)
			(size 1.8034 0.508)
			(layers "F.Cu" "F.Mask" "F.Paste")
			(net "M_G_DQ<19>")
		)
		(pad "35" smd rect
			(at 0 28.90012 90)
			(size 1.8034 0.508)
			(layers "F.Cu" "F.Mask" "F.Paste")
			(net "GND")
		)
		(pad "36" smd rect
			(at 0 29.750004 90)
			(size 1.8034 0.508)
			(layers "F.Cu" "F.Mask" "F.Paste")
			(net "M_G_DQ<29>")
		)
		(pad "37" smd rect
			(at 0 30.599888 90)
			(size 1.8034 0.508)
			(layers "F.Cu" "F.Mask" "F.Paste")
			(net "GND")
		)
		(pad "38" smd rect
			(at 0 31.450026 90)
			(size 1.8034 0.508)
			(layers "F.Cu" "F.Mask" "F.Paste")
			(net "M_G_DQ<25>")
		)
		(pad "39" smd rect
			(at 0 32.29991 90)
			(size 1.8034 0.508)
			(layers "F.Cu" "F.Mask" "F.Paste")
			(net "GND")
		)
		(pad "40" smd rect
			(at 0 33.150048 90)
			(size 1.8034 0.508)
			(layers "F.Cu" "F.Mask" "F.Paste")
			(net "M_G_DQS_DP<12>")
		)
		(pad "41" smd rect
			(at 0 33.999932 90)
			(size 1.8034 0.508)
			(layers "F.Cu" "F.Mask" "F.Paste")
			(net "M_G_DQS_DN<12>")
		)
		(pad "42" smd rect
			(at 0 34.85007 90)
			(size 1.8034 0.508)
			(layers "F.Cu" "F.Mask" "F.Paste")
			(net "GND")
		)
		(pad "43" smd rect
			(at 0 35.699954 90)
			(size 1.8034 0.508)
			(layers "F.Cu" "F.Mask" "F.Paste")
			(net "M_G_DQ<31>")
		)
		(pad "44" smd rect
			(at 0 36.550092 90)
			(size 1.8034 0.508)
			(layers "F.Cu" "F.Mask" "F.Paste")
			(net "GND")
		)
		(pad "45" smd rect
			(at 0 37.399976 90)
			(size 1.8034 0.508)
			(layers "F.Cu" "F.Mask" "F.Paste")
			(net "M_G_DQ<27>")
		)
		(pad "46" smd rect
			(at 0 38.250114 90)
			(size 1.8034 0.508)
			(layers "F.Cu" "F.Mask" "F.Paste")
			(net "GND")
		)
		(pad "47" smd rect
			(at 0 39.099998 90)
			(size 1.8034 0.508)
			(layers "F.Cu" "F.Mask" "F.Paste")
			(net "M_G_ECC<5>")
		)
	)
)
